# SCM (Grand Teton) — schematic netlist excerpt (pin names and nets, part order shuffled) for the footprints in the layout excerpt that follows; sources: Cadence DE-HDL packaged netlist, KiCad conversion of 12092022_DA0F0TMDCD0_F0T_Management_Board_D_brd_V3_OCP.brd

R247  Q_RES  2.2K 5% CHIP  pkg 0402LF  page 27 : A = P3V3_AUX ; B = SMB_BMC_MM2_SDA

X19  TP_TDR_4P_FTS  TP_TDR_4P_DIP EMPTY  pkg TH  page 60
  S1  = TDR_DIFF_100_TOP_DN
  P1  = GND_P1
  P2  = GND_P1
  S2  = TDR_DIFF_100_TOP_DP

(kicad_pcb
	(version 20260206)
	(generator "pcbnew")
	(generator_version "10.0")
	(general
		(thickness 1.6)
		(legacy_teardrops no)
	)
	(paper "A4")
	(title_block
		(title "12092022_DA0F0TMDCD0_F0T_Management_Board_D_brd_V3_OCP.brd")
		(comment 1 "Grand Teton / footprints 837-838 of 1440")
	)
	(layers
		(0 "F.Cu" signal "TOP")
		(4 "In1.Cu" signal "GND")
		(6 "In2.Cu" signal "IN1")
		(8 "In3.Cu" signal "GND1")
		(10 "In4.Cu" signal "IN2")
		(12 "In5.Cu" signal "VCC")
		(14 "In6.Cu" signal "VCC1")
		(16 "In7.Cu" signal "IN3")
		(18 "In8.Cu" signal "GND2")
		(20 "In9.Cu" signal "IN4")
		(22 "In10.Cu" signal "GND3")
		(2 "B.Cu" signal "BOTTOM")
		(9 "F.Adhes" user "F.Adhesive")
		(11 "B.Adhes" user "B.Adhesive")
		(13 "F.Paste" user "Package Geometry/Pastemask Top")
		(15 "B.Paste" user "Package Geometry/Pastemask Bottom")
		(5 "F.SilkS" user "Ref Des/Silkscreen Top")
		(7 "B.SilkS" user "Ref Des/Silkscreen Bottom")
		(1 "F.Mask" user "Board Geometry/Soldermask Top")
		(3 "B.Mask" user "Board Geometry/Soldermask Bottom")
		(17 "Dwgs.User" user "User.Drawings")
		(19 "Cmts.User" user "User.Comments")
		(21 "Eco1.User" user "User.Eco1")
		(23 "Eco2.User" user "User.Eco2")
		(25 "Edge.Cuts" user "Board Geometry/Outline")
		(27 "Margin" user)
		(31 "F.CrtYd" user "Package Geometry/Place Bound Top")
		(29 "B.CrtYd" user "Package Geometry/Place Bound Bottom")
		(35 "F.Fab" user "Ref Des/Assembly Top")
		(33 "B.Fab" user "Ref Des/Assembly Bottom")
	)
	(footprint ""
		(layer "B.Cu")
		(at 114.554 4.572 -90)
		(property "Reference" "X19"
			(at 2.07137 1.4605 0)
			(unlocked yes)
			(layer "B.SilkS")
			(effects
				(font
					(size 0.7874 0.5842)
					(thickness 0.1524)
				)
				(justify left mirror)
			)
		)
		(property "Value" ""
			(at 0 0 90)
			(layer "B.Fab")
			(effects
				(font
					(size 1.27 1.27)
				)
				(justify mirror)
			)
		)
		(property "Device Type" "TP_TDR_4P_FTS_TH-TP_TDR_4P_DIPA"
			(at -1.30175 1.27 180)
			(unlocked yes)
			(layer "B.Fab")
			(hide yes)
			(effects
				(font
					(size 0.635 0.4064)
					(thickness 0.1524)
				)
				(justify mirror)
			)
		)
		(property "User Part Number" "N_A"
			(at -1.30175 1.27 180)
			(unlocked yes)
			(layer "Cmts.User")
			(hide yes)
			(effects
				(font
					(size 0.635 0.4064)
					(thickness 0.1524)
				)
				(justify mirror)
			)
		)
		(duplicate_pad_numbers_are_jumpers no)
		(fp_line
			(start -2.54 3.81)
			(end -2.54 3.6703)
			(stroke
				(width 0.1524)
				(type default)
			)
			(layer "B.SilkS")
		)
		(fp_line
			(start 0 3.81)
			(end -2.54 3.81)
			(stroke
				(width 0.1524)
				(type default)
			)
			(layer "B.SilkS")
		)
		(fp_line
			(start 0 3.175)
			(end 0 3.81)
			(stroke
				(width 0.1524)
				(type default)
			)
			(layer "B.SilkS")
		)
		(fp_line
			(start -2.54 1.4097)
			(end -2.54 1.1303)
			(stroke
				(width 0.1524)
				(type default)
			)
			(layer "B.SilkS")
		)
		(fp_line
			(start 0 0.635)
			(end 0 1.905)
			(stroke
				(width 0.1524)
				(type default)
			)
			(layer "B.SilkS")
		)
		(fp_line
			(start -2.54 -1.1303)
			(end -2.54 -1.27)
			(stroke
				(width 0.1524)
				(type default)
			)
			(layer "B.SilkS")
		)
		(fp_line
			(start -2.54 -1.27)
			(end 0 -1.27)
			(stroke
				(width 0.1524)
				(type default)
			)
			(layer "B.SilkS")
		)
		(fp_line
			(start 0 -1.27)
			(end 0 -0.635)
			(stroke
				(width 0.1524)
				(type default)
			)
			(layer "B.SilkS")
		)
		(fp_poly
			(pts
				(xy 0.761746 0) (xy 2.285746 -0.762) (xy 2.285746 0.762)
			)
			(stroke
				(width 0)
				(type default)
			)
			(fill yes)
			(layer "B.SilkS")
		)
		(fp_line
			(start -2.54 3.81)
			(end -2.54 -1.27)
			(stroke
				(width 0.1)
				(type default)
			)
			(layer "B.Fab")
		)
		(fp_line
			(start 0 3.81)
			(end -2.54 3.81)
			(stroke
				(width 0.1)
				(type default)
			)
			(layer "B.Fab")
		)
		(fp_line
			(start -2.54 -1.27)
			(end 0 -1.27)
			(stroke
				(width 0.1)
				(type default)
			)
			(layer "B.Fab")
		)
		(fp_line
			(start 0 -1.27)
			(end 0 3.81)
			(stroke
				(width 0.1)
				(type default)
			)
			(layer "B.Fab")
		)
		(fp_poly
			(pts
				(xy 0.761746 0) (xy 2.285746 -0.762) (xy 2.285746 0.762)
			)
			(stroke
				(width 0)
				(type default)
			)
			(fill yes)
			(layer "B.Fab")
		)
		(pad "1" thru_hole circle
			(at 0 0 90)
			(size 1.0033 1.0033)
			(drill 0.249936)
			(layers "*.Cu" "*.Mask")
			(remove_unused_layers no)
			(net "TDR_DIFF_100_TOP_DN")
			(clearance 0.10795)
			(padstack
				(mode front_inner_back)
				(layer "Inner"
					(shape circle)
					(size 0.8001 0.8001)
					(clearance 0.1524)
				)
				(layer "B.Cu"
					(shape circle)
					(size 1.0033 1.0033)
					(thermal_gap 0.10795)
					(clearance 0.10795)
				)
			)
		)
		(pad "2" thru_hole circle
			(at -2.54 0 90)
			(size 1.9939 1.9939)
			(drill 0.249936)
			(layers "*.Cu" "*.Mask")
			(remove_unused_layers no)
			(net "GND_P1")
			(clearance 0.10795)
			(padstack
				(mode front_inner_back)
				(layer "Inner"
					(shape circle)
					(size 0.8001 0.8001)
					(clearance 0.1524)
				)
				(layer "B.Cu"
					(shape circle)
					(size 1.9939 1.9939)
					(thermal_gap 0.10795)
					(clearance 0.10795)
				)
			)
		)
		(pad "3" thru_hole circle
			(at -2.54 2.54 90)
			(size 1.9939 1.9939)
			(drill 0.249936)
			(layers "*.Cu" "*.Mask")
			(remove_unused_layers no)
			(net "GND_P1")
			(clearance 0.10795)
			(padstack
				(mode front_inner_back)
				(layer "Inner"
					(shape circle)
					(size 0.8001 0.8001)
					(clearance 0.1524)
				)
				(layer "B.Cu"
					(shape circle)
					(size 1.9939 1.9939)
					(thermal_gap 0.10795)
					(clearance 0.10795)
				)
			)
		)
		(pad "4" thru_hole circle
			(at 0 2.54 90)
			(size 1.0033 1.0033)
			(drill 0.249936)
			(layers "*.Cu" "*.Mask")
			(remove_unused_layers no)
			(net "TDR_DIFF_100_TOP_DP")
			(clearance 0.10795)
			(padstack
				(mode front_inner_back)
				(layer "Inner"
					(shape circle)
					(size 0.8001 0.8001)
					(clearance 0.1524)
				)
				(layer "B.Cu"
					(shape circle)
					(size 1.0033 1.0033)
					(thermal_gap 0.10795)
					(clearance 0.10795)
				)
			)
		)
	)
	(footprint ""
		(layer "B.Cu")
		(at 43.367452 -30.816804 -90)
		(property "Reference" "R247"
			(at 0 0 90)
			(layer "B.SilkS")
			(hide yes)
			(effects
				(font
					(size 1.27 1.27)
				)
				(justify mirror)
			)
		)
		(property "Value" ""
			(at 0 0 90)
			(layer "B.Fab")
			(effects
				(font
					(size 1.27 1.27)
				)
				(justify mirror)
			)
		)
		(duplicate_pad_numbers_are_jumpers no)
		(fp_line
			(start -0.7874 0.4064)
			(end 0.7874 0.4064)
			(stroke
				(width 0.1524)
				(type default)
			)
			(layer "B.SilkS")
		)
		(fp_line
			(start 0.7874 0.4064)
			(end 0.7874 -0.4064)
			(stroke
				(width 0.1524)
				(type default)
			)
			(layer "B.SilkS")
		)
		(fp_line
			(start -0.7874 -0.4064)
			(end -0.7874 0.4064)
			(stroke
				(width 0.1524)
				(type default)
			)
			(layer "B.SilkS")
		)
		(fp_line
			(start 0.7874 -0.4064)
			(end -0.7874 -0.4064)
			(stroke
				(width 0.1524)
				(type default)
			)
			(layer "B.SilkS")
		)
		(fp_line
			(start -0.67945 0.3048)
			(end -0.120396 0.3048)
			(stroke
				(width 0.1)
				(type default)
			)
			(layer "B.Fab")
		)
		(fp_line
			(start -0.120396 0.3048)
			(end -0.120396 0.2794)
			(stroke
				(width 0.1)
				(type default)
			)
			(layer "B.Fab")
		)
		(fp_line
			(start 0.12065 0.3048)
			(end 0.67945 0.3048)
			(stroke
				(width 0.1)
				(type default)
			)
			(layer "B.Fab")
		)
		(fp_line
			(start 0.67945 0.3048)
			(end 0.67945 -0.305054)
			(stroke
				(width 0.1)
				(type default)
			)
			(layer "B.Fab")
		)
		(fp_line
			(start -0.120396 0.2794)
			(end 0.12065 0.2794)
			(stroke
				(width 0.1)
				(type default)
			)
			(layer "B.Fab")
		)
		(fp_line
			(start 0.12065 0.2794)
			(end 0.12065 0.3048)
			(stroke
				(width 0.1)
				(type default)
			)
			(layer "B.Fab")
		)
		(fp_line
			(start -0.12065 -0.2794)
			(end -0.12065 -0.3048)
			(stroke
				(width 0.1)
				(type default)
			)
			(layer "B.Fab")
		)
		(fp_line
			(start 0.12065 -0.2794)
			(end -0.12065 -0.2794)
			(stroke
				(width 0.1)
				(type default)
			)
			(layer "B.Fab")
		)
		(fp_line
			(start -0.67945 -0.3048)
			(end -0.67945 0.3048)
			(stroke
				(width 0.1)
				(type default)
			)
			(layer "B.Fab")
		)
		(fp_line
			(start -0.12065 -0.3048)
			(end -0.67945 -0.3048)
			(stroke
				(width 0.1)
				(type default)
			)
			(layer "B.Fab")
		)
		(fp_line
			(start 0.12065 -0.305054)
			(end 0.12065 -0.2794)
			(stroke
				(width 0.1)
				(type default)
			)
			(layer "B.Fab")
		)
		(fp_line
			(start 0.67945 -0.305054)
			(end 0.12065 -0.305054)
			(stroke
				(width 0.1)
				(type default)
			)
			(layer "B.Fab")
		)
		(pad "1" smd circle
			(at 0.40005 0 90)
			(size 0 0)
			(layers "B.Cu" "B.Mask" "B.Paste")
			(net "P3V3_AUX")
		)
		(pad "2" smd circle
			(at -0.40005 0 90)
			(size 0 0)
			(layers "B.Cu" "B.Mask" "B.Paste")
			(net "SMB_BMC_MM2_SDA")
		)
	)
)
